(kicad_pcb
	(version 20260206)
	(generator "pcbnew")
	(generator_version "10.0")
	(general
		(thickness 1.6)
		(legacy_teardrops no)
	)
	(paper "A4")
	(title_block
		(title "04192023_DAF0TMB3IC0_F0TG_MB_C_brd_V02_OCP.brd")
		(comment 1 "Grand Teton / footprints 357-364 of 8354")
	)
	(layers
		(0 "F.Cu" signal "TOP")
		(4 "In1.Cu" signal "GND")
		(6 "In2.Cu" signal "IN1")
		(8 "In3.Cu" signal "GND1")
		(10 "In4.Cu" signal "IN2")
		(12 "In5.Cu" signal "GND2")
		(14 "In6.Cu" signal "IN3")
		(16 "In7.Cu" signal "GND3")
		(18 "In8.Cu" signal "VCC")
		(20 "In9.Cu" signal "VCC1")
		(22 "In10.Cu" signal "GND4")
		(24 "In11.Cu" signal "IN4")
		(26 "In12.Cu" signal "GND5")
		(28 "In13.Cu" signal "IN5")
		(30 "In14.Cu" signal "GND6")
		(32 "In15.Cu" signal "IN6")
		(34 "In16.Cu" signal "GND7")
		(2 "B.Cu" signal "BOTTOM")
		(9 "F.Adhes" user "F.Adhesive")
		(11 "B.Adhes" user "B.Adhesive")
		(13 "F.Paste" user "Package Geometry/Pastemask Top")
		(15 "B.Paste" user "Package Geometry/Pastemask Bottom")
		(5 "F.SilkS" user "Ref Des/Silkscreen Top")
		(7 "B.SilkS" user "Ref Des/Silkscreen Bottom")
		(1 "F.Mask" user "Board Geometry/Soldermask Top")
		(3 "B.Mask" user "Board Geometry/Soldermask Bottom")
		(17 "Dwgs.User" user "User.Drawings")
		(19 "Cmts.User" user "User.Comments")
		(21 "Eco1.User" user "User.Eco1")
		(23 "Eco2.User" user "User.Eco2")
		(25 "Edge.Cuts" user "Board Geometry/Outline")
		(27 "Margin" user)
		(31 "F.CrtYd" user "Package Geometry/Place Bound Top")
		(29 "B.CrtYd" user "Package Geometry/Place Bound Bottom")
		(35 "F.Fab" user "Ref Des/Assembly Top")
		(33 "B.Fab" user "Ref Des/Assembly Bottom")
	)
	(footprint ""
		(layer "F.Cu")
		(at 367.050066 -427.400212 -90)
		(property "Reference" "R4206"
			(at 0 0 270)
			(layer "F.SilkS")
			(hide yes)
			(effects
				(font
					(size 1.27 1.27)
				)
			)
		)
		(property "Value" ""
			(at 0 0 270)
			(layer "F.Fab")
			(effects
				(font
					(size 1.27 1.27)
				)
			)
		)
		(duplicate_pad_numbers_are_jumpers no)
		(fp_line
			(start -0.7874 0.4064)
			(end -0.7874 -0.4064)
			(stroke
				(width 0.1524)
				(type default)
			)
			(layer "F.SilkS")
		)
		(fp_line
			(start 0.7874 0.4064)
			(end -0.7874 0.4064)
			(stroke
				(width 0.1524)
				(type default)
			)
			(layer "F.SilkS")
		)
		(fp_line
			(start -0.7874 -0.4064)
			(end 0.7874 -0.4064)
			(stroke
				(width 0.1524)
				(type default)
			)
			(layer "F.SilkS")
		)
		(fp_line
			(start 0.7874 -0.4064)
			(end 0.7874 0.4064)
			(stroke
				(width 0.1524)
				(type default)
			)
			(layer "F.SilkS")
		)
		(fp_line
			(start -0.67945 0.3048)
			(end -0.67945 -0.305054)
			(stroke
				(width 0.1)
				(type default)
			)
			(layer "F.Fab")
		)
		(fp_line
			(start -0.12065 0.3048)
			(end -0.67945 0.3048)
			(stroke
				(width 0.1)
				(type default)
			)
			(layer "F.Fab")
		)
		(fp_line
			(start 0.120396 0.3048)
			(end 0.120396 0.2794)
			(stroke
				(width 0.1)
				(type default)
			)
			(layer "F.Fab")
		)
		(fp_line
			(start 0.67945 0.3048)
			(end 0.120396 0.3048)
			(stroke
				(width 0.1)
				(type default)
			)
			(layer "F.Fab")
		)
		(fp_line
			(start -0.12065 0.2794)
			(end -0.12065 0.3048)
			(stroke
				(width 0.1)
				(type default)
			)
			(layer "F.Fab")
		)
		(fp_line
			(start 0.120396 0.2794)
			(end -0.12065 0.2794)
			(stroke
				(width 0.1)
				(type default)
			)
			(layer "F.Fab")
		)
		(fp_line
			(start -0.12065 -0.2794)
			(end 0.12065 -0.2794)
			(stroke
				(width 0.1)
				(type default)
			)
			(layer "F.Fab")
		)
		(fp_line
			(start 0.12065 -0.2794)
			(end 0.12065 -0.3048)
			(stroke
				(width 0.1)
				(type default)
			)
			(layer "F.Fab")
		)
		(fp_line
			(start 0.12065 -0.3048)
			(end 0.67945 -0.3048)
			(stroke
				(width 0.1)
				(type default)
			)
			(layer "F.Fab")
		)
		(fp_line
			(start 0.67945 -0.3048)
			(end 0.67945 0.3048)
			(stroke
				(width 0.1)
				(type default)
			)
			(layer "F.Fab")
		)
		(fp_line
			(start -0.67945 -0.305054)
			(end -0.12065 -0.305054)
			(stroke
				(width 0.1)
				(type default)
			)
			(layer "F.Fab")
		)
		(fp_line
			(start -0.12065 -0.305054)
			(end -0.12065 -0.2794)
			(stroke
				(width 0.1)
				(type default)
			)
			(layer "F.Fab")
		)
		(pad "1" smd circle
			(at -0.40005 0 270)
			(size 0 0)
			(layers "F.Cu" "F.Mask" "F.Paste")
			(net "P3V3_AUX")
		)
		(pad "2" smd circle
			(at 0.40005 0 270)
			(size 0 0)
			(layers "F.Cu" "F.Mask" "F.Paste")
			(net "U270_0_ADD0")
		)
	)
	(footprint ""
		(layer "F.Cu")
		(at 116.078 -417.957 -90)
		(property "Reference" "R3030"
			(at 0 0 270)
			(layer "F.SilkS")
			(hide yes)
			(effects
				(font
					(size 1.27 1.27)
				)
			)
		)
		(property "Value" ""
			(at 0 0 270)
			(layer "F.Fab")
			(effects
				(font
					(size 1.27 1.27)
				)
			)
		)
		(duplicate_pad_numbers_are_jumpers no)
		(fp_line
			(start -0.7874 0.4064)
			(end -0.7874 -0.4064)
			(stroke
				(width 0.1524)
				(type default)
			)
			(layer "F.SilkS")
		)
		(fp_line
			(start 0.7874 0.4064)
			(end -0.7874 0.4064)
			(stroke
				(width 0.1524)
				(type default)
			)
			(layer "F.SilkS")
		)
		(fp_line
			(start -0.7874 -0.4064)
			(end 0.7874 -0.4064)
			(stroke
				(width 0.1524)
				(type default)
			)
			(layer "F.SilkS")
		)
		(fp_line
			(start 0.7874 -0.4064)
			(end 0.7874 0.4064)
			(stroke
				(width 0.1524)
				(type default)
			)
			(layer "F.SilkS")
		)
		(fp_line
			(start -0.67945 0.3048)
			(end -0.67945 -0.305054)
			(stroke
				(width 0.1)
				(type default)
			)
			(layer "F.Fab")
		)
		(fp_line
			(start -0.12065 0.3048)
			(end -0.67945 0.3048)
			(stroke
				(width 0.1)
				(type default)
			)
			(layer "F.Fab")
		)
		(fp_line
			(start 0.120396 0.3048)
			(end 0.120396 0.2794)
			(stroke
				(width 0.1)
				(type default)
			)
			(layer "F.Fab")
		)
		(fp_line
			(start 0.67945 0.3048)
			(end 0.120396 0.3048)
			(stroke
				(width 0.1)
				(type default)
			)
			(layer "F.Fab")
		)
		(fp_line
			(start -0.12065 0.2794)
			(end -0.12065 0.3048)
			(stroke
				(width 0.1)
				(type default)
			)
			(layer "F.Fab")
		)
		(fp_line
			(start 0.120396 0.2794)
			(end -0.12065 0.2794)
			(stroke
				(width 0.1)
				(type default)
			)
			(layer "F.Fab")
		)
		(fp_line
			(start -0.12065 -0.2794)
			(end 0.12065 -0.2794)
			(stroke
				(width 0.1)
				(type default)
			)
			(layer "F.Fab")
		)
		(fp_line
			(start 0.12065 -0.2794)
			(end 0.12065 -0.3048)
			(stroke
				(width 0.1)
				(type default)
			)
			(layer "F.Fab")
		)
		(fp_line
			(start 0.12065 -0.3048)
			(end 0.67945 -0.3048)
			(stroke
				(width 0.1)
				(type default)
			)
			(layer "F.Fab")
		)
		(fp_line
			(start 0.67945 -0.3048)
			(end 0.67945 0.3048)
			(stroke
				(width 0.1)
				(type default)
			)
			(layer "F.Fab")
		)
		(fp_line
			(start -0.67945 -0.305054)
			(end -0.12065 -0.305054)
			(stroke
				(width 0.1)
				(type default)
			)
			(layer "F.Fab")
		)
		(fp_line
			(start -0.12065 -0.305054)
			(end -0.12065 -0.2794)
			(stroke
				(width 0.1)
				(type default)
			)
			(layer "F.Fab")
		)
		(pad "1" smd circle
			(at -0.40005 0 270)
			(size 0 0)
			(layers "F.Cu" "F.Mask" "F.Paste")
			(net "P3V3_AUX")
		)
		(pad "2" smd circle
			(at 0.40005 0 270)
			(size 0 0)
			(layers "F.Cu" "F.Mask" "F.Paste")
			(net "FM_SMB_1_ALERT_GPU_ISO_N")
		)
	)
	(footprint ""
		(layer "F.Cu")
		(at 409.8417 -171.598082)
		(property "Reference" "PC187"
			(at 0 0 0)
			(layer "F.SilkS")
			(hide yes)
			(effects
				(font
					(size 1.27 1.27)
				)
			)
		)
		(property "Value" ""
			(at 0 0 0)
			(layer "F.Fab")
			(effects
				(font
					(size 1.27 1.27)
				)
			)
		)
		(duplicate_pad_numbers_are_jumpers no)
		(fp_line
			(start -0.7874 -0.4064)
			(end 0.7874 -0.4064)
			(stroke
				(width 0.1524)
				(type default)
			)
			(layer "F.SilkS")
		)
		(fp_line
			(start -0.7874 0.4064)
			(end -0.7874 -0.4064)
			(stroke
				(width 0.1524)
				(type default)
			)
			(layer "F.SilkS")
		)
		(fp_line
			(start 0.7874 -0.4064)
			(end 0.7874 0.4064)
			(stroke
				(width 0.1524)
				(type default)
			)
			(layer "F.SilkS")
		)
		(fp_line
			(start 0.7874 0.4064)
			(end -0.7874 0.4064)
			(stroke
				(width 0.1524)
				(type default)
			)
			(layer "F.SilkS")
		)
		(fp_line
			(start -0.67945 -0.305054)
			(end -0.12065 -0.305054)
			(stroke
				(width 0.1)
				(type default)
			)
			(layer "F.Fab")
		)
		(fp_line
			(start -0.67945 0.3048)
			(end -0.67945 -0.305054)
			(stroke
				(width 0.1)
				(type default)
			)
			(layer "F.Fab")
		)
		(fp_line
			(start -0.12065 -0.305054)
			(end -0.12065 -0.2794)
			(stroke
				(width 0.1)
				(type default)
			)
			(layer "F.Fab")
		)
		(fp_line
			(start -0.12065 -0.2794)
			(end 0.12065 -0.2794)
			(stroke
				(width 0.1)
				(type default)
			)
			(layer "F.Fab")
		)
		(fp_line
			(start -0.12065 0.2794)
			(end -0.12065 0.3048)
			(stroke
				(width 0.1)
				(type default)
			)
			(layer "F.Fab")
		)
		(fp_line
			(start -0.12065 0.3048)
			(end -0.67945 0.3048)
			(stroke
				(width 0.1)
				(type default)
			)
			(layer "F.Fab")
		)
		(fp_line
			(start 0.120396 0.2794)
			(end -0.12065 0.2794)
			(stroke
				(width 0.1)
				(type default)
			)
			(layer "F.Fab")
		)
		(fp_line
			(start 0.120396 0.3048)
			(end 0.120396 0.2794)
			(stroke
				(width 0.1)
				(type default)
			)
			(layer "F.Fab")
		)
		(fp_line
			(start 0.12065 -0.3048)
			(end 0.67945 -0.3048)
			(stroke
				(width 0.1)
				(type default)
			)
			(layer "F.Fab")
		)
		(fp_line
			(start 0.12065 -0.2794)
			(end 0.12065 -0.3048)
			(stroke
				(width 0.1)
				(type default)
			)
			(layer "F.Fab")
		)
		(fp_line
			(start 0.67945 -0.3048)
			(end 0.67945 0.3048)
			(stroke
				(width 0.1)
				(type default)
			)
			(layer "F.Fab")
		)
		(fp_line
			(start 0.67945 0.3048)
			(end 0.120396 0.3048)
			(stroke
				(width 0.1)
				(type default)
			)
			(layer "F.Fab")
		)
		(pad "1" smd circle
			(at -0.40005 0)
			(size 0 0)
			(layers "F.Cu" "F.Mask" "F.Paste")
			(net "SW_PVDDCR_SOC_P0_SW2")
		)
		(pad "2" smd circle
			(at 0.40005 0)
			(size 0 0)
			(layers "F.Cu" "F.Mask" "F.Paste")
			(net "SW_PVDDCR_SOC_P0_SW2_RC")
		)
	)
	(footprint ""
		(layer "F.Cu")
		(at 136.118092 -159.535368)
		(property "Reference" "PC195"
			(at 0 0 0)
			(layer "F.SilkS")
			(hide yes)
			(effects
				(font
					(size 1.27 1.27)
				)
			)
		)
		(property "Value" ""
			(at 0 0 0)
			(layer "F.Fab")
			(effects
				(font
					(size 1.27 1.27)
				)
			)
		)
		(duplicate_pad_numbers_are_jumpers no)
		(fp_line
			(start -0.7874 -0.4064)
			(end 0.7874 -0.4064)
			(stroke
				(width 0.1524)
				(type default)
			)
			(layer "F.SilkS")
		)
		(fp_line
			(start -0.7874 0.4064)
			(end -0.7874 -0.4064)
			(stroke
				(width 0.1524)
				(type default)
			)
			(layer "F.SilkS")
		)
		(fp_line
			(start 0.7874 -0.4064)
			(end 0.7874 0.4064)
			(stroke
				(width 0.1524)
				(type default)
			)
			(layer "F.SilkS")
		)
		(fp_line
			(start 0.7874 0.4064)
			(end -0.7874 0.4064)
			(stroke
				(width 0.1524)
				(type default)
			)
			(layer "F.SilkS")
		)
		(fp_line
			(start -0.67945 -0.305054)
			(end -0.12065 -0.305054)
			(stroke
				(width 0.1)
				(type default)
			)
			(layer "F.Fab")
		)
		(fp_line
			(start -0.67945 0.3048)
			(end -0.67945 -0.305054)
			(stroke
				(width 0.1)
				(type default)
			)
			(layer "F.Fab")
		)
		(fp_line
			(start -0.12065 -0.305054)
			(end -0.12065 -0.2794)
			(stroke
				(width 0.1)
				(type default)
			)
			(layer "F.Fab")
		)
		(fp_line
			(start -0.12065 -0.2794)
			(end 0.12065 -0.2794)
			(stroke
				(width 0.1)
				(type default)
			)
			(layer "F.Fab")
		)
		(fp_line
			(start -0.12065 0.2794)
			(end -0.12065 0.3048)
			(stroke
				(width 0.1)
				(type default)
			)
			(layer "F.Fab")
		)
		(fp_line
			(start -0.12065 0.3048)
			(end -0.67945 0.3048)
			(stroke
				(width 0.1)
				(type default)
			)
			(layer "F.Fab")
		)
		(fp_line
			(start 0.120396 0.2794)
			(end -0.12065 0.2794)
			(stroke
				(width 0.1)
				(type default)
			)
			(layer "F.Fab")
		)
		(fp_line
			(start 0.120396 0.3048)
			(end 0.120396 0.2794)
			(stroke
				(width 0.1)
				(type default)
			)
			(layer "F.Fab")
		)
		(fp_line
			(start 0.12065 -0.3048)
			(end 0.67945 -0.3048)
			(stroke
				(width 0.1)
				(type default)
			)
			(layer "F.Fab")
		)
		(fp_line
			(start 0.12065 -0.2794)
			(end 0.12065 -0.3048)
			(stroke
				(width 0.1)
				(type default)
			)
			(layer "F.Fab")
		)
		(fp_line
			(start 0.67945 -0.3048)
			(end 0.67945 0.3048)
			(stroke
				(width 0.1)
				(type default)
			)
			(layer "F.Fab")
		)
		(fp_line
			(start 0.67945 0.3048)
			(end 0.120396 0.3048)
			(stroke
				(width 0.1)
				(type default)
			)
			(layer "F.Fab")
		)
		(pad "1" smd circle
			(at -0.40005 0)
			(size 0 0)
			(layers "F.Cu" "F.Mask" "F.Paste")
			(net "SW_PVDDCR_SOC_P1_SW3")
		)
		(pad "2" smd circle
			(at 0.40005 0)
			(size 0 0)
			(layers "F.Cu" "F.Mask" "F.Paste")
			(net "SW_PVDDCR_SOC_P1_SW3_RC")
		)
	)
	(footprint ""
		(layer "F.Cu")
		(at 385.723892 -383.88163 -90)
		(property "Reference" "C880"
			(at 0 0 270)
			(layer "F.SilkS")
			(hide yes)
			(effects
				(font
					(size 1.27 1.27)
				)
			)
		)
		(property "Value" ""
			(at 0 0 270)
			(layer "F.Fab")
			(effects
				(font
					(size 1.27 1.27)
				)
			)
		)
		(duplicate_pad_numbers_are_jumpers no)
		(fp_line
			(start -0.299974 0.150114)
			(end -0.299974 -0.150114)
			(stroke
				(width 0.1)
				(type default)
			)
			(layer "F.Fab")
		)
		(fp_line
			(start 0.299974 0.150114)
			(end -0.299974 0.150114)
			(stroke
				(width 0.1)
				(type default)
			)
			(layer "F.Fab")
		)
		(fp_line
			(start -0.299974 -0.150114)
			(end 0.299974 -0.150114)
			(stroke
				(width 0.1)
				(type default)
			)
			(layer "F.Fab")
		)
		(fp_line
			(start 0.299974 -0.150114)
			(end 0.299974 0.150114)
			(stroke
				(width 0.1)
				(type default)
			)
			(layer "F.Fab")
		)
		(pad "1" smd rect
			(at -0.2667 0 270)
			(size 0.3048 0.381)
			(layers "F.Cu" "F.Mask" "F.Paste")
			(net "P5E_CPU0_P3_TX_C_DN<10>")
		)
		(pad "2" smd rect
			(at 0.2667 0 270)
			(size 0.3048 0.381)
			(layers "F.Cu" "F.Mask" "F.Paste")
			(net "P5E_CPU0_P3_TX_DN<10>")
		)
	)
	(footprint ""
		(layer "F.Cu")
		(at 139.544552 -382.00584)
		(property "Reference" "R949"
			(at 0 0 0)
			(layer "F.SilkS")
			(hide yes)
			(effects
				(font
					(size 1.27 1.27)
				)
			)
		)
		(property "Value" ""
			(at 0 0 0)
			(layer "F.Fab")
			(effects
				(font
					(size 1.27 1.27)
				)
			)
		)
		(duplicate_pad_numbers_are_jumpers no)
		(fp_line
			(start -0.32512 -0.175006)
			(end 0.32512 -0.175006)
			(stroke
				(width 0.1)
				(type default)
			)
			(layer "F.Fab")
		)
		(fp_line
			(start -0.32512 0.175006)
			(end -0.32512 -0.175006)
			(stroke
				(width 0.1)
				(type default)
			)
			(layer "F.Fab")
		)
		(fp_line
			(start 0.32512 -0.175006)
			(end 0.32512 0.175006)
			(stroke
				(width 0.1)
				(type default)
			)
			(layer "F.Fab")
		)
		(fp_line
			(start 0.32512 0.175006)
			(end -0.32512 0.175006)
			(stroke
				(width 0.1)
				(type default)
			)
			(layer "F.Fab")
		)
		(pad "1" smd rect
			(at -0.2667 0)
			(size 0.3048 0.381)
			(layers "F.Cu" "F.Mask" "F.Paste")
			(net "RT_CPU1_P3_ADDR1")
		)
		(pad "2" smd rect
			(at 0.2667 0 180)
			(size 0.3048 0.381)
			(layers "F.Cu" "F.Mask" "F.Paste")
			(net "GND")
		)
	)
	(footprint ""
		(layer "F.Cu")
		(at 96.853502 -373.03583 -90)
		(property "Reference" "C718"
			(at 0 0 270)
			(layer "F.SilkS")
			(hide yes)
			(effects
				(font
					(size 1.27 1.27)
				)
			)
		)
		(property "Value" ""
			(at 0 0 270)
			(layer "F.Fab")
			(effects
				(font
					(size 1.27 1.27)
				)
			)
		)
		(duplicate_pad_numbers_are_jumpers no)
		(fp_line
			(start -0.299974 0.150114)
			(end -0.299974 -0.150114)
			(stroke
				(width 0.1)
				(type default)
			)
			(layer "F.Fab")
		)
		(fp_line
			(start 0.299974 0.150114)
			(end -0.299974 0.150114)
			(stroke
				(width 0.1)
				(type default)
			)
			(layer "F.Fab")
		)
		(fp_line
			(start -0.299974 -0.150114)
			(end 0.299974 -0.150114)
			(stroke
				(width 0.1)
				(type default)
			)
			(layer "F.Fab")
		)
		(fp_line
			(start 0.299974 -0.150114)
			(end 0.299974 0.150114)
			(stroke
				(width 0.1)
				(type default)
			)
			(layer "F.Fab")
		)
		(pad "1" smd rect
			(at -0.2667 0 270)
			(size 0.3048 0.381)
			(layers "F.Cu" "F.Mask" "F.Paste")
			(net "P5E_CPU1_P1_TX_C_DN<11>")
		)
		(pad "2" smd rect
			(at 0.2667 0 270)
			(size 0.3048 0.381)
			(layers "F.Cu" "F.Mask" "F.Paste")
			(net "P5E_CPU1_P1_TX_DN<11>")
		)
	)
	(footprint ""
		(layer "F.Cu")
		(at 204.954886 -111.665512 180)
		(property "Reference" "R1563"
			(at 0 0 180)
			(layer "F.SilkS")
			(hide yes)
			(effects
				(font
					(size 1.27 1.27)
				)
			)
		)
		(property "Value" ""
			(at 0 0 180)
			(layer "F.Fab")
			(effects
				(font
					(size 1.27 1.27)
				)
			)
		)
		(duplicate_pad_numbers_are_jumpers no)
		(fp_line
			(start 0.7874 0.4064)
			(end -0.7874 0.4064)
			(stroke
				(width 0.1524)
				(type default)
			)
			(layer "F.SilkS")
		)
		(fp_line
			(start 0.7874 -0.4064)
			(end 0.7874 0.4064)
			(stroke
				(width 0.1524)
				(type default)
			)
			(layer "F.SilkS")
		)
		(fp_line
			(start -0.7874 0.4064)
			(end -0.7874 -0.4064)
			(stroke
				(width 0.1524)
				(type default)
			)
			(layer "F.SilkS")
		)
		(fp_line
			(start -0.7874 -0.4064)
			(end 0.7874 -0.4064)
			(stroke
				(width 0.1524)
				(type default)
			)
			(layer "F.SilkS")
		)
		(fp_line
			(start 0.67945 0.3048)
			(end 0.120396 0.3048)
			(stroke
				(width 0.1)
				(type default)
			)
			(layer "F.Fab")
		)
		(fp_line
			(start 0.67945 -0.3048)
			(end 0.67945 0.3048)
			(stroke
				(width 0.1)
				(type default)
			)
			(layer "F.Fab")
		)
		(fp_line
			(start 0.12065 -0.2794)
			(end 0.12065 -0.3048)
			(stroke
				(width 0.1)
				(type default)
			)
			(layer "F.Fab")
		)
		(fp_line
			(start 0.12065 -0.3048)
			(end 0.67945 -0.3048)
			(stroke
				(width 0.1)
				(type default)
			)
			(layer "F.Fab")
		)
		(fp_line
			(start 0.120396 0.3048)
			(end 0.120396 0.2794)
			(stroke
				(width 0.1)
				(type default)
			)
			(layer "F.Fab")
		)
		(fp_line
			(start 0.120396 0.2794)
			(end -0.12065 0.2794)
			(stroke
				(width 0.1)
				(type default)
			)
			(layer "F.Fab")
		)
		(fp_line
			(start -0.12065 0.3048)
			(end -0.67945 0.3048)
			(stroke
				(width 0.1)
				(type default)
			)
			(layer "F.Fab")
		)
		(fp_line
			(start -0.12065 0.2794)
			(end -0.12065 0.3048)
			(stroke
				(width 0.1)
				(type default)
			)
			(layer "F.Fab")
		)
		(fp_line
			(start -0.12065 -0.2794)
			(end 0.12065 -0.2794)
			(stroke
				(width 0.1)
				(type default)
			)
			(layer "F.Fab")
		)
		(fp_line
			(start -0.12065 -0.305054)
			(end -0.12065 -0.2794)
			(stroke
				(width 0.1)
				(type default)
			)
			(layer "F.Fab")
		)
		(fp_line
			(start -0.67945 0.3048)
			(end -0.67945 -0.305054)
			(stroke
				(width 0.1)
				(type default)
			)
			(layer "F.Fab")
		)
		(fp_line
			(start -0.67945 -0.305054)
			(end -0.12065 -0.305054)
			(stroke
				(width 0.1)
				(type default)
			)
			(layer "F.Fab")
		)
		(pad "1" smd circle
			(at -0.40005 0 180)
			(size 0 0)
			(layers "F.Cu" "F.Mask" "F.Paste")
			(net "UART_LS_EN")
		)
		(pad "2" smd circle
			(at 0.40005 0 180)
			(size 0 0)
			(layers "F.Cu" "F.Mask" "F.Paste")
			(net "FM_UART_LS_EN")
		)
	)
)
